FILE_TYPE=LIBRARY_PARTS;
TIME=' COMPILATION ON MON JAN  3 13:57:57 1994  ';
primitive 'CHOKE_4PIN','CHOKE_4PIN_SM';
  pin
    'A1':
      PIN_NUMBER='(1)';
      PIN_TYPE='ANALOG';
      NO_LOAD_CHECK='BOTH';
      NO_IO_CHECK='BOTH';
      ALLOW_CONNECT='TRUE';
    'A2':
      PIN_NUMBER='(2)';
      PIN_TYPE='ANALOG';
      NO_LOAD_CHECK='BOTH';
      NO_IO_CHECK='BOTH';
      ALLOW_CONNECT='TRUE';
    'B1':
      PIN_NUMBER='(3)';
      PIN_TYPE='ANALOG';
      NO_LOAD_CHECK='BOTH';
      NO_IO_CHECK='BOTH';
      ALLOW_CONNECT='TRUE';
    'B2':
      PIN_NUMBER='(4)';
      PIN_TYPE='ANALOG';
      NO_LOAD_CHECK='BOTH';
      NO_IO_CHECK='BOTH';
      ALLOW_CONNECT='TRUE';
  end_pin;
  body
   PART_NAME='CHOKE_4PIN';
   PHYS_DES_PREFIX='L';
  end_body;
end_primitive;

primitive 'CHOKE_4PIN_SM_B','CHOKE_4PIN_SM_C';
  pin
    '1':
      PIN_NUMBER='(1)';
      PIN_TYPE='ANALOG';
      NO_LOAD_CHECK='BOTH';
      NO_IO_CHECK='BOTH';
      ALLOW_CONNECT='TRUE';
    '2':
      PIN_NUMBER='(2)';
      PIN_TYPE='ANALOG';
      NO_LOAD_CHECK='BOTH';
      NO_IO_CHECK='BOTH';
      ALLOW_CONNECT='TRUE';
    '3':
      PIN_NUMBER='(3)';
      PIN_TYPE='ANALOG';
      NO_LOAD_CHECK='BOTH';
      NO_IO_CHECK='BOTH';
      ALLOW_CONNECT='TRUE';
    '4':
      PIN_NUMBER='(4)';
      PIN_TYPE='ANALOG';
      NO_LOAD_CHECK='BOTH';
      NO_IO_CHECK='BOTH';
      ALLOW_CONNECT='TRUE';
  end_pin;
  body
    PART_NAME='CHOKE_4PIN';
    PHYS_DES_PREFIX='L';
  end_body;
end_primitive;


END.

